# T6G (Grand Teton) — schematic netlist excerpt (pin names and nets, part order shuffled) for the footprints in the layout excerpt that follows; sources: Cadence DE-HDL packaged netlist, KiCad conversion of 04192023_DAF0TMB3IC0_F0TG_MB_C_brd_V02_OCP.brd

PC268_1  Q_CAP  22UF 16V 20% X6S  pkg C0805  page 211 : A = SW_P12V_AUX_PVDDCR_CPU0_P1_FLT ; B = GND
R2935  Q_RES  100K 1% CHIP  pkg 0402LF  page 127 : A = P3V3_AUX ; B = FM_GPU_PWRGD_ISO
R6032  Q_RES  0 5% CHIP  pkg 0402LF  page 150 : A = JTAG_SCM_DBREQ_N ; B = SCM_HDT_DBREQ_N

(kicad_pcb
	(version 20260206)
	(generator "pcbnew")
	(generator_version "10.0")
	(general
		(thickness 1.6)
		(legacy_teardrops no)
	)
	(paper "A4")
	(title_block
		(title "04192023_DAF0TMB3IC0_F0TG_MB_C_brd_V02_OCP.brd")
		(comment 1 "Grand Teton / footprints 8326-8328 of 8354")
	)
	(layers
		(0 "F.Cu" signal "TOP")
		(4 "In1.Cu" signal "GND")
		(6 "In2.Cu" signal "IN1")
		(8 "In3.Cu" signal "GND1")
		(10 "In4.Cu" signal "IN2")
		(12 "In5.Cu" signal "GND2")
		(14 "In6.Cu" signal "IN3")
		(16 "In7.Cu" signal "GND3")
		(18 "In8.Cu" signal "VCC")
		(20 "In9.Cu" signal "VCC1")
		(22 "In10.Cu" signal "GND4")
		(24 "In11.Cu" signal "IN4")
		(26 "In12.Cu" signal "GND5")
		(28 "In13.Cu" signal "IN5")
		(30 "In14.Cu" signal "GND6")
		(32 "In15.Cu" signal "IN6")
		(34 "In16.Cu" signal "GND7")
		(2 "B.Cu" signal "BOTTOM")
		(9 "F.Adhes" user "F.Adhesive")
		(11 "B.Adhes" user "B.Adhesive")
		(13 "F.Paste" user "Package Geometry/Pastemask Top")
		(15 "B.Paste" user "Package Geometry/Pastemask Bottom")
		(5 "F.SilkS" user "Ref Des/Silkscreen Top")
		(7 "B.SilkS" user "Ref Des/Silkscreen Bottom")
		(1 "F.Mask" user "Board Geometry/Soldermask Top")
		(3 "B.Mask" user "Board Geometry/Soldermask Bottom")
		(17 "Dwgs.User" user "User.Drawings")
		(19 "Cmts.User" user "User.Comments")
		(21 "Eco1.User" user "User.Eco1")
		(23 "Eco2.User" user "User.Eco2")
		(25 "Edge.Cuts" user "Board Geometry/Outline")
		(27 "Margin" user)
		(31 "F.CrtYd" user "Package Geometry/Place Bound Top")
		(29 "B.CrtYd" user "Package Geometry/Place Bound Bottom")
		(35 "F.Fab" user "Ref Des/Assembly Top")
		(33 "B.Fab" user "Ref Des/Assembly Bottom")
	)
	(footprint ""
		(layer "B.Cu")
		(at 79.225648 -182.656734 -90)
		(property "Reference" "PC268_1"
			(at 0 0 90)
			(layer "B.SilkS")
			(hide yes)
			(effects
				(font
					(size 1.27 1.27)
				)
				(justify mirror)
			)
		)
		(property "Value" ""
			(at 0 0 90)
			(layer "B.Fab")
			(effects
				(font
					(size 1.27 1.27)
				)
				(justify mirror)
			)
		)
		(duplicate_pad_numbers_are_jumpers no)
		(fp_line
			(start -1.524 0.762)
			(end 1.524 0.762)
			(stroke
				(width 0.1524)
				(type default)
			)
			(layer "B.SilkS")
		)
		(fp_line
			(start 1.524 0.762)
			(end 1.524 -0.762)
			(stroke
				(width 0.1524)
				(type default)
			)
			(layer "B.SilkS")
		)
		(fp_line
			(start -1.524 -0.762)
			(end -1.524 0.762)
			(stroke
				(width 0.1524)
				(type default)
			)
			(layer "B.SilkS")
		)
		(fp_line
			(start 1.524 -0.762)
			(end -1.524 -0.762)
			(stroke
				(width 0.1524)
				(type default)
			)
			(layer "B.SilkS")
		)
		(fp_line
			(start -1.1049 0.724916)
			(end -1.1049 -0.724916)
			(stroke
				(width 0.1)
				(type default)
			)
			(layer "B.Fab")
		)
		(fp_line
			(start 1.1049 0.724916)
			(end -1.1049 0.724916)
			(stroke
				(width 0.1)
				(type default)
			)
			(layer "B.Fab")
		)
		(fp_line
			(start -1.1049 -0.724916)
			(end 1.1049 -0.724916)
			(stroke
				(width 0.1)
				(type default)
			)
			(layer "B.Fab")
		)
		(fp_line
			(start 1.1049 -0.724916)
			(end 1.1049 0.724916)
			(stroke
				(width 0.1)
				(type default)
			)
			(layer "B.Fab")
		)
		(pad "1" smd rect
			(at 0.889 0 270)
			(size 1.016 1.27)
			(layers "B.Cu" "B.Mask" "B.Paste")
			(net "SW_P12V_AUX_PVDDCR_CPU0_P1_FLT")
		)
		(pad "2" smd rect
			(at -0.889 0 270)
			(size 1.016 1.27)
			(layers "B.Cu" "B.Mask" "B.Paste")
			(net "GND")
		)
	)
	(footprint ""
		(layer "B.Cu")
		(at 52.74564 -424.225212 -90)
		(property "Reference" "R2935"
			(at 0 0 90)
			(layer "B.SilkS")
			(hide yes)
			(effects
				(font
					(size 1.27 1.27)
				)
				(justify mirror)
			)
		)
		(property "Value" ""
			(at 0 0 90)
			(layer "B.Fab")
			(effects
				(font
					(size 1.27 1.27)
				)
				(justify mirror)
			)
		)
		(duplicate_pad_numbers_are_jumpers no)
		(fp_line
			(start -0.7874 0.4064)
			(end 0.7874 0.4064)
			(stroke
				(width 0.1524)
				(type default)
			)
			(layer "B.SilkS")
		)
		(fp_line
			(start 0.7874 0.4064)
			(end 0.7874 -0.4064)
			(stroke
				(width 0.1524)
				(type default)
			)
			(layer "B.SilkS")
		)
		(fp_line
			(start -0.7874 -0.4064)
			(end -0.7874 0.4064)
			(stroke
				(width 0.1524)
				(type default)
			)
			(layer "B.SilkS")
		)
		(fp_line
			(start 0.7874 -0.4064)
			(end -0.7874 -0.4064)
			(stroke
				(width 0.1524)
				(type default)
			)
			(layer "B.SilkS")
		)
		(fp_line
			(start -0.67945 0.3048)
			(end -0.120396 0.3048)
			(stroke
				(width 0.1)
				(type default)
			)
			(layer "B.Fab")
		)
		(fp_line
			(start -0.120396 0.3048)
			(end -0.120396 0.2794)
			(stroke
				(width 0.1)
				(type default)
			)
			(layer "B.Fab")
		)
		(fp_line
			(start 0.12065 0.3048)
			(end 0.67945 0.3048)
			(stroke
				(width 0.1)
				(type default)
			)
			(layer "B.Fab")
		)
		(fp_line
			(start 0.67945 0.3048)
			(end 0.67945 -0.305054)
			(stroke
				(width 0.1)
				(type default)
			)
			(layer "B.Fab")
		)
		(fp_line
			(start -0.120396 0.2794)
			(end 0.12065 0.2794)
			(stroke
				(width 0.1)
				(type default)
			)
			(layer "B.Fab")
		)
		(fp_line
			(start 0.12065 0.2794)
			(end 0.12065 0.3048)
			(stroke
				(width 0.1)
				(type default)
			)
			(layer "B.Fab")
		)
		(fp_line
			(start -0.12065 -0.2794)
			(end -0.12065 -0.3048)
			(stroke
				(width 0.1)
				(type default)
			)
			(layer "B.Fab")
		)
		(fp_line
			(start 0.12065 -0.2794)
			(end -0.12065 -0.2794)
			(stroke
				(width 0.1)
				(type default)
			)
			(layer "B.Fab")
		)
		(fp_line
			(start -0.67945 -0.3048)
			(end -0.67945 0.3048)
			(stroke
				(width 0.1)
				(type default)
			)
			(layer "B.Fab")
		)
		(fp_line
			(start -0.12065 -0.3048)
			(end -0.67945 -0.3048)
			(stroke
				(width 0.1)
				(type default)
			)
			(layer "B.Fab")
		)
		(fp_line
			(start 0.12065 -0.305054)
			(end 0.12065 -0.2794)
			(stroke
				(width 0.1)
				(type default)
			)
			(layer "B.Fab")
		)
		(fp_line
			(start 0.67945 -0.305054)
			(end 0.12065 -0.305054)
			(stroke
				(width 0.1)
				(type default)
			)
			(layer "B.Fab")
		)
		(pad "1" smd circle
			(at 0.40005 0 90)
			(size 0 0)
			(layers "B.Cu" "B.Mask" "B.Paste")
			(net "P3V3_AUX")
		)
		(pad "2" smd circle
			(at -0.40005 0 90)
			(size 0 0)
			(layers "B.Cu" "B.Mask" "B.Paste")
			(net "FM_GPU_PWRGD_ISO")
		)
	)
	(footprint ""
		(layer "B.Cu")
		(at 142.2908 -13.763752 90)
		(property "Reference" "R6032"
			(at 0 0 90)
			(layer "B.SilkS")
			(hide yes)
			(effects
				(font
					(size 1.27 1.27)
				)
				(justify mirror)
			)
		)
		(property "Value" ""
			(at 0 0 90)
			(layer "B.Fab")
			(effects
				(font
					(size 1.27 1.27)
				)
				(justify mirror)
			)
		)
		(duplicate_pad_numbers_are_jumpers no)
		(fp_line
			(start 0.7874 -0.4064)
			(end -0.7874 -0.4064)
			(stroke
				(width 0.1524)
				(type default)
			)
			(layer "B.SilkS")
		)
		(fp_line
			(start -0.7874 -0.4064)
			(end -0.7874 0.4064)
			(stroke
				(width 0.1524)
				(type default)
			)
			(layer "B.SilkS")
		)
		(fp_line
			(start 0.7874 0.4064)
			(end 0.7874 -0.4064)
			(stroke
				(width 0.1524)
				(type default)
			)
			(layer "B.SilkS")
		)
		(fp_line
			(start -0.7874 0.4064)
			(end 0.7874 0.4064)
			(stroke
				(width 0.1524)
				(type default)
			)
			(layer "B.SilkS")
		)
		(fp_line
			(start 0.67945 -0.305054)
			(end 0.12065 -0.305054)
			(stroke
				(width 0.1)
				(type default)
			)
			(layer "B.Fab")
		)
		(fp_line
			(start 0.12065 -0.305054)
			(end 0.12065 -0.2794)
			(stroke
				(width 0.1)
				(type default)
			)
			(layer "B.Fab")
		)
		(fp_line
			(start -0.12065 -0.3048)
			(end -0.67945 -0.3048)
			(stroke
				(width 0.1)
				(type default)
			)
			(layer "B.Fab")
		)
		(fp_line
			(start -0.67945 -0.3048)
			(end -0.67945 0.3048)
			(stroke
				(width 0.1)
				(type default)
			)
			(layer "B.Fab")
		)
		(fp_line
			(start 0.12065 -0.2794)
			(end -0.12065 -0.2794)
			(stroke
				(width 0.1)
				(type default)
			)
			(layer "B.Fab")
		)
		(fp_line
			(start -0.12065 -0.2794)
			(end -0.12065 -0.3048)
			(stroke
				(width 0.1)
				(type default)
			)
			(layer "B.Fab")
		)
		(fp_line
			(start 0.12065 0.2794)
			(end 0.12065 0.3048)
			(stroke
				(width 0.1)
				(type default)
			)
			(layer "B.Fab")
		)
		(fp_line
			(start -0.120396 0.2794)
			(end 0.12065 0.2794)
			(stroke
				(width 0.1)
				(type default)
			)
			(layer "B.Fab")
		)
		(fp_line
			(start 0.67945 0.3048)
			(end 0.67945 -0.305054)
			(stroke
				(width 0.1)
				(type default)
			)
			(layer "B.Fab")
		)
		(fp_line
			(start 0.12065 0.3048)
			(end 0.67945 0.3048)
			(stroke
				(width 0.1)
				(type default)
			)
			(layer "B.Fab")
		)
		(fp_line
			(start -0.120396 0.3048)
			(end -0.120396 0.2794)
			(stroke
				(width 0.1)
				(type default)
			)
			(layer "B.Fab")
		)
		(fp_line
			(start -0.67945 0.3048)
			(end -0.120396 0.3048)
			(stroke
				(width 0.1)
				(type default)
			)
			(layer "B.Fab")
		)
		(pad "1" smd circle
			(at 0.40005 0 270)
			(size 0 0)
			(layers "B.Cu" "B.Mask" "B.Paste")
			(net "JTAG_SCM_DBREQ_N")
		)
		(pad "2" smd circle
			(at -0.40005 0 270)
			(size 0 0)
			(layers "B.Cu" "B.Mask" "B.Paste")
			(net "SCM_HDT_DBREQ_N")
		)
	)
)
